# S9S_MB_2U (Grand Teton) — schematic netlist excerpt (pin names and nets, part order shuffled) for the footprints in the layout excerpt that follows; sources: Cadence DE-HDL packaged netlist, KiCad conversion of 03242023_DA0F0TMBIJ0_F0T_Motherboard_J_brd_V01_OCP.brd

R1718  Q_RES  49.9 1% CHIP  pkg 0402LF  page 296 : A = PVNN_TERM_CPU1 ; B = SVID_CLK1_CPU1_R
PC1322  Q_CAP  100PF 50V 5% EMPTY  pkg 0402  page 163 : A = P3V3_OCP_GATE_PU207_2 ; B = GND

(kicad_pcb
	(version 20260206)
	(generator "pcbnew")
	(generator_version "10.0")
	(general
		(thickness 1.6)
		(legacy_teardrops no)
	)
	(paper "A4")
	(title_block
		(title "03242023_DA0F0TMBIJ0_F0T_Motherboard_J_brd_V01_OCP.brd")
		(comment 1 "Grand Teton / footprints 802-803 of 6105")
	)
	(layers
		(0 "F.Cu" signal "TOP")
		(4 "In1.Cu" signal "GND")
		(6 "In2.Cu" signal "IN1")
		(8 "In3.Cu" signal "GND1")
		(10 "In4.Cu" signal "IN2")
		(12 "In5.Cu" signal "GND2")
		(14 "In6.Cu" signal "IN3")
		(16 "In7.Cu" signal "GND3")
		(18 "In8.Cu" signal "VCC")
		(20 "In9.Cu" signal "VCC1")
		(22 "In10.Cu" signal "GND4")
		(24 "In11.Cu" signal "IN4")
		(26 "In12.Cu" signal "GND5")
		(28 "In13.Cu" signal "IN5")
		(30 "In14.Cu" signal "GND6")
		(32 "In15.Cu" signal "IN6")
		(34 "In16.Cu" signal "GND7")
		(2 "B.Cu" signal "BOTTOM")
		(9 "F.Adhes" user "F.Adhesive")
		(11 "B.Adhes" user "B.Adhesive")
		(13 "F.Paste" user "Package Geometry/Pastemask Top")
		(15 "B.Paste" user "Package Geometry/Pastemask Bottom")
		(5 "F.SilkS" user "Ref Des/Silkscreen Top")
		(7 "B.SilkS" user "Ref Des/Silkscreen Bottom")
		(1 "F.Mask" user "Board Geometry/Soldermask Top")
		(3 "B.Mask" user "Board Geometry/Soldermask Bottom")
		(17 "Dwgs.User" user "User.Drawings")
		(19 "Cmts.User" user "User.Comments")
		(21 "Eco1.User" user "User.Eco1")
		(23 "Eco2.User" user "User.Eco2")
		(25 "Edge.Cuts" user "Board Geometry/Outline")
		(27 "Margin" user)
		(31 "F.CrtYd" user "Package Geometry/Place Bound Top")
		(29 "B.CrtYd" user "Package Geometry/Place Bound Bottom")
		(35 "F.Fab" user "Ref Des/Assembly Top")
		(33 "B.Fab" user "Ref Des/Assembly Bottom")
	)
	(footprint ""
		(layer "F.Cu")
		(at 70.41896 -61.158628 90)
		(property "Reference" "PC1322"
			(at 0 0 90)
			(layer "F.SilkS")
			(hide yes)
			(effects
				(font
					(size 1.27 1.27)
				)
			)
		)
		(property "Value" ""
			(at 0 0 90)
			(layer "F.Fab")
			(effects
				(font
					(size 1.27 1.27)
				)
			)
		)
		(duplicate_pad_numbers_are_jumpers no)
		(fp_line
			(start 0.7874 -0.4064)
			(end 0.7874 0.4064)
			(stroke
				(width 0.1524)
				(type default)
			)
			(layer "F.SilkS")
		)
		(fp_line
			(start -0.7874 -0.4064)
			(end 0.7874 -0.4064)
			(stroke
				(width 0.1524)
				(type default)
			)
			(layer "F.SilkS")
		)
		(fp_line
			(start 0.7874 0.4064)
			(end -0.7874 0.4064)
			(stroke
				(width 0.1524)
				(type default)
			)
			(layer "F.SilkS")
		)
		(fp_line
			(start -0.7874 0.4064)
			(end -0.7874 -0.4064)
			(stroke
				(width 0.1524)
				(type default)
			)
			(layer "F.SilkS")
		)
		(fp_line
			(start -0.12065 -0.305054)
			(end -0.12065 -0.2794)
			(stroke
				(width 0.1)
				(type default)
			)
			(layer "F.Fab")
		)
		(fp_line
			(start -0.67945 -0.305054)
			(end -0.12065 -0.305054)
			(stroke
				(width 0.1)
				(type default)
			)
			(layer "F.Fab")
		)
		(fp_line
			(start 0.67945 -0.3048)
			(end 0.67945 0.3048)
			(stroke
				(width 0.1)
				(type default)
			)
			(layer "F.Fab")
		)
		(fp_line
			(start 0.12065 -0.3048)
			(end 0.67945 -0.3048)
			(stroke
				(width 0.1)
				(type default)
			)
			(layer "F.Fab")
		)
		(fp_line
			(start 0.12065 -0.2794)
			(end 0.12065 -0.3048)
			(stroke
				(width 0.1)
				(type default)
			)
			(layer "F.Fab")
		)
		(fp_line
			(start -0.12065 -0.2794)
			(end 0.12065 -0.2794)
			(stroke
				(width 0.1)
				(type default)
			)
			(layer "F.Fab")
		)
		(fp_line
			(start 0.120396 0.2794)
			(end -0.12065 0.2794)
			(stroke
				(width 0.1)
				(type default)
			)
			(layer "F.Fab")
		)
		(fp_line
			(start -0.12065 0.2794)
			(end -0.12065 0.3048)
			(stroke
				(width 0.1)
				(type default)
			)
			(layer "F.Fab")
		)
		(fp_line
			(start 0.67945 0.3048)
			(end 0.120396 0.3048)
			(stroke
				(width 0.1)
				(type default)
			)
			(layer "F.Fab")
		)
		(fp_line
			(start 0.120396 0.3048)
			(end 0.120396 0.2794)
			(stroke
				(width 0.1)
				(type default)
			)
			(layer "F.Fab")
		)
		(fp_line
			(start -0.12065 0.3048)
			(end -0.67945 0.3048)
			(stroke
				(width 0.1)
				(type default)
			)
			(layer "F.Fab")
		)
		(fp_line
			(start -0.67945 0.3048)
			(end -0.67945 -0.305054)
			(stroke
				(width 0.1)
				(type default)
			)
			(layer "F.Fab")
		)
		(pad "1" smd circle
			(at -0.40005 0 90)
			(size 0 0)
			(layers "F.Cu" "F.Mask" "F.Paste")
			(net "P3V3_OCP_GATE_PU207_2")
		)
		(pad "2" smd circle
			(at 0.40005 0 90)
			(size 0 0)
			(layers "F.Cu" "F.Mask" "F.Paste")
			(net "GND")
		)
	)
	(footprint ""
		(layer "F.Cu")
		(at 20.11426 -165.751256)
		(property "Reference" "R1718"
			(at 0 0 0)
			(layer "F.SilkS")
			(hide yes)
			(effects
				(font
					(size 1.27 1.27)
				)
			)
		)
		(property "Value" ""
			(at 0 0 0)
			(layer "F.Fab")
			(effects
				(font
					(size 1.27 1.27)
				)
			)
		)
		(duplicate_pad_numbers_are_jumpers no)
		(fp_line
			(start -0.7874 -0.4064)
			(end 0.7874 -0.4064)
			(stroke
				(width 0.1524)
				(type default)
			)
			(layer "F.SilkS")
		)
		(fp_line
			(start -0.7874 0.4064)
			(end -0.7874 -0.4064)
			(stroke
				(width 0.1524)
				(type default)
			)
			(layer "F.SilkS")
		)
		(fp_line
			(start 0.7874 -0.4064)
			(end 0.7874 0.4064)
			(stroke
				(width 0.1524)
				(type default)
			)
			(layer "F.SilkS")
		)
		(fp_line
			(start 0.7874 0.4064)
			(end -0.7874 0.4064)
			(stroke
				(width 0.1524)
				(type default)
			)
			(layer "F.SilkS")
		)
		(fp_line
			(start -0.67945 -0.305054)
			(end -0.12065 -0.305054)
			(stroke
				(width 0.1)
				(type default)
			)
			(layer "F.Fab")
		)
		(fp_line
			(start -0.67945 0.3048)
			(end -0.67945 -0.305054)
			(stroke
				(width 0.1)
				(type default)
			)
			(layer "F.Fab")
		)
		(fp_line
			(start -0.12065 -0.305054)
			(end -0.12065 -0.2794)
			(stroke
				(width 0.1)
				(type default)
			)
			(layer "F.Fab")
		)
		(fp_line
			(start -0.12065 -0.2794)
			(end 0.12065 -0.2794)
			(stroke
				(width 0.1)
				(type default)
			)
			(layer "F.Fab")
		)
		(fp_line
			(start -0.12065 0.2794)
			(end -0.12065 0.3048)
			(stroke
				(width 0.1)
				(type default)
			)
			(layer "F.Fab")
		)
		(fp_line
			(start -0.12065 0.3048)
			(end -0.67945 0.3048)
			(stroke
				(width 0.1)
				(type default)
			)
			(layer "F.Fab")
		)
		(fp_line
			(start 0.120396 0.2794)
			(end -0.12065 0.2794)
			(stroke
				(width 0.1)
				(type default)
			)
			(layer "F.Fab")
		)
		(fp_line
			(start 0.120396 0.3048)
			(end 0.120396 0.2794)
			(stroke
				(width 0.1)
				(type default)
			)
			(layer "F.Fab")
		)
		(fp_line
			(start 0.12065 -0.3048)
			(end 0.67945 -0.3048)
			(stroke
				(width 0.1)
				(type default)
			)
			(layer "F.Fab")
		)
		(fp_line
			(start 0.12065 -0.2794)
			(end 0.12065 -0.3048)
			(stroke
				(width 0.1)
				(type default)
			)
			(layer "F.Fab")
		)
		(fp_line
			(start 0.67945 -0.3048)
			(end 0.67945 0.3048)
			(stroke
				(width 0.1)
				(type default)
			)
			(layer "F.Fab")
		)
		(fp_line
			(start 0.67945 0.3048)
			(end 0.120396 0.3048)
			(stroke
				(width 0.1)
				(type default)
			)
			(layer "F.Fab")
		)
		(pad "1" smd circle
			(at -0.40005 0)
			(size 0 0)
			(layers "F.Cu" "F.Mask" "F.Paste")
			(net "PVNN_TERM_CPU1")
		)
		(pad "2" smd circle
			(at 0.40005 0)
			(size 0 0)
			(layers "F.Cu" "F.Mask" "F.Paste")
			(net "SVID_CLK1_CPU1_R")
		)
	)
)
